# T6G (Grand Teton) — schematic parts with pin connectivity, parts 6524–6677 of 8303; source: Cadence DE-HDL packaged netlist (pstxprt.dat, pstxnet.dat, pstchip.dat)

R2812  Q_RES  33.2 1% CHIP  pkg 0402LF  page 240 : 1 = SMB_FAN_3V3AUX_BUF_SDA ; 2 = SMB_FAN_3V3AUX_BUF_R_SDA
R2815  Q_RES  100K 1% EMPTY  pkg 0402LF  page 130 : 1 = P3V3_AUX ; 2 = BMC_MONITER_R
R2820  Q_RES  4.7K 5% EMPTY  pkg 0402LF  page 130 : 1 = P3V3_AUX ; 2 = BMC_MONITER_BUF_R
R2828  Q_RES  100K 1% CHIP  pkg 0402LF  page 127 : 1 = P3V3_AUX ; 2 = RST_BMC_FROM_SWB_N
R2829  Q_RES  100K 1% EMPTY  pkg 0402LF  page 127 : 1 = RST_BMC_FROM_SWB_N ; 2 = GND
R2830  Q_RES  100K 1% CHIP  pkg 0402LF  page 127 : 1 = P3V3_AUX ; 2 = BIC_MONITER
R2831  Q_RES  100K 1% EMPTY  pkg 0402LF  page 127 : 1 = BIC_MONITER ; 2 = GND
R2832  Q_RES  100K 1% CHIP  pkg 0402LF  page 127 : 1 = P3V3_AUX ; 2 = FM_SWB_BIC_READY_N
R2833  Q_RES  100K 1% EMPTY  pkg 0402LF  page 127 : 1 = FM_SWB_BIC_READY_N ; 2 = GND
R2834  Q_RES  4.7K 5% CHIP  pkg 0402LF  page 127 : 1 = P3V3_AUX ; 2 = RST_BMC_FROM_SWB
R2835  Q_RES  4.7K 5% CHIP  pkg 0402LF  page 127 : 1 = P3V3_AUX ; 2 = BIC_MONITER_N
R2836  Q_RES  4.7K 5% CHIP  pkg 0402LF  page 127 : 1 = P3V3_AUX ; 2 = FM_SWB_BIC_READY
R2837  Q_RES  100K 1% EMPTY  pkg 0402LF  page 127 : 1 = P3V3_AUX ; 2 = FM_SWB_PWRGD
R2838  Q_RES  100K 1% CHIP  pkg 0402LF  page 127 : 1 = FM_SWB_PWRGD ; 2 = GND
R2841  Q_RES  4.7K 5% CHIP  pkg 0402LF  page 127 : 1 = P3V3_AUX ; 2 = FM_SWB_PWRGD_N
R2842  Q_RES  4.7K 5% CHIP  pkg 0402LF  page 127 : 1 = P3V3_AUX ; 2 = FM_GPU_PWRGD_N
R2843  Q_RES  4.7K 1% CHIP  pkg 0402LF  page 257 : 1 = P3V3_ADC ; 2 = GND
R2844  Q_RES  33.2 1% CHIP  pkg 0402LF  page 81 : 1 = FM_SWB_BIC_READY_ISO_R_N ; 2 = FM_SWB_BIC_READY_ISO_N
R2845  Q_RES  33.2 1% CHIP  pkg 0402LF  page 81 : 1 = BMC_MONITER_R ; 2 = BMC_MONITER
R2846  Q_RES  33.2 1% CHIP  pkg 0402LF  page 81 : 1 = BIC_MONITER_ISO_R ; 2 = BIC_MONITER_ISO
R2847  Q_RES  33.2 1% CHIP  pkg 0402LF  page 81 : 1 = RST_BMC_FROM_SWB_ISO_R_N ; 2 = RST_BMC_FROM_SWB_ISO_N
R2848  Q_RES  0 5% CHIP  pkg 0402LF  page 245 : 1 = RST_SWB_BIC_N ; 2 = RST_SWB_BIC_R_N
R2893  Q_RES  0 5% EMPTY  pkg 0402LF  page 248 : 1 = SMB_1_BMC_GPU_R_SCL ; 2 = SMB_1_BMC_GPU_BUF_R_SCL
R2894  Q_RES  0 5% EMPTY  pkg 0402LF  page 248 : 1 = SMB_1_BMC_GPU_R_SDA ; 2 = SMB_1_BMC_GPU_BUF_R_SDA
R2897  Q_RES  33.2 1% CHIP  pkg 0402LF  page 248 : 1 = SMB_1_BMC_GPU_BUF_R_SCL ; 2 = SMB_1_BMC_GPU_BUF_SCL
R2898  Q_RES  33.2 1% CHIP  pkg 0402LF  page 248 : 1 = SMB_1_BMC_GPU_BUF_R_SDA ; 2 = SMB_1_BMC_GPU_BUF_SDA
R2899  Q_RES  0 5% CHIP  pkg 0402LF  page 248 : 1 = SMB_BMC_GPU_EN ; 2 = SMB_BMC_GPU_EN_R1
R2900  Q_RES  2K 1% CHIP  pkg 0402LF  page 257 : 1 = MAX11617_VREF ; 2 = MAX11617_VREF_R
R2905  Q_RES  0 5% CHIP  pkg 0402LF  page 240 : 1 = RST_SMB_SWITCH_N ; 2 = RST_SMB_SWITCH_R_N
R2906  Q_RES  0 5% CHIP  pkg 0402LF  page 240 : 1 = FM_GPU_HSC_EN_BUF_R1 ; 2 = FM_GPU_HSC_EN_BUF
R2907  Q_RES  5.11K 1% CHIP  pkg 0402LF  page 257 : 1 = P3V3_AUX ; 2 = P3V3_AUX_ADC
R2908  Q_RES  5.11K 1% CHIP  pkg 0402LF  page 257 : 1 = P3V3 ; 2 = P3V3_ADC
R2909  Q_RES  4.7K 5% CHIP  pkg 0402LF  page 130 : 1 = P3V3_AUX ; 2 = RST_SWB_BIC_R_N
R2910  Q_RES  100K 1% EMPTY  pkg 0402LF  page 128 : 1 = P3V3_AUX ; 2 = FM_SWB_PWR_EN_R
R2911  Q_RES  4.7K 5% EMPTY  pkg 0402LF  page 130 : 1 = P3V3_AUX ; 2 = RST_SWB_BIC_BUF_R_N
R2912  Q_RES  4.7K 5% EMPTY  pkg 0402LF  page 130 : 1 = P3V3_AUX ; 2 = FM_GPU_PWR_EN_R1
R2914  Q_RES  4.7K 5% EMPTY  pkg 0402LF  page 128 : 1 = P3V3_AUX ; 2 = FM_SWB_PWR_EN_R1_BUF
R2915  Q_RES  4.7K 5% CHIP  pkg 0402LF  page 130 : 1 = BMC_MONITER_R ; 2 = GND
R2916  Q_RES  4.7K 5% EMPTY  pkg 0402LF  page 130 : 1 = RST_SWB_BIC_R_N ; 2 = GND
R2917  Q_RES  49.9 1% CHIP  pkg 0402LF  page 130 : 1 = BMC_MONITER_BUF_R ; 2 = BMC_MONITER_BUF
R2918  Q_RES  4.7K 5% CHIP  pkg 0402LF  page 128 : 1 = FM_SWB_PWR_EN_R ; 2 = GND
R2919  Q_RES  100K 1% CHIP  pkg 0402LF  page 127 : 1 = P3V3_AUX ; 2 = RST_BMC_FROM_SWB_ISO_N
R2920  Q_RES  100K 1% CHIP  pkg 0402LF  page 127 : 1 = P3V3_AUX ; 2 = BIC_MONITER_ISO
R2921  Q_RES  10K 1% EMPTY  pkg 0402LF  page 245 : 1 = P3V3_AUX ; 2 = RST_SMB_SWITCH_N
R2922  Q_RES  0 5% CHIP  pkg 0402LF  page 245 : 1 = RST_SMB_SWITCH_N ; 2 = PU_RST_SMB_U181_N
R2923  Q_RES  4.7K 5% EMPTY  pkg 0402LF  page 245 : 1 = P3V3_AUX ; 2 = PU_U181_INT
R2924  Q_RES  49.9 1% CHIP  pkg 0402LF  page 130 : 1 = RST_SWB_BIC_BUF_R_N ; 2 = RST_SWB_BIC_BUF_N
R2925  Q_RES  49.9 1% CHIP  pkg 0402LF  page 130 : 1 = FM_GPU_PWR_EN_R1 ; 2 = FM_GPU_PWR_EN_R_BUF
R2926  Q_RES  4.7K 5% CHIP  pkg 0402LF  page 130 : 1 = BMC_MONITER_BUF_R ; 2 = GND
R2927  Q_RES  100K 1% CHIP  pkg 0402LF  page 130 : 1 = RST_SWB_BIC_BUF_R_N ; 2 = GND
R2932  Q_RES  4.7K 5% CHIP  pkg 0402LF  page 128 : 1 = FM_SWB_PWR_EN_R1_BUF ; 2 = GND
R2933  Q_RES  100K 1% CHIP  pkg 0402LF  page 127 : 1 = P3V3_AUX ; 2 = FM_SWB_BIC_READY_ISO_N
R2934  Q_RES  100K 1% CHIP  pkg 0402LF  page 127 : 1 = P3V3_AUX ; 2 = FM_SWB_PWRGD_ISO
R2935  Q_RES  100K 1% CHIP  pkg 0402LF  page 127 : 1 = P3V3_AUX ; 2 = FM_GPU_PWRGD_ISO
R2936  Q_RES  100K 1% EMPTY  pkg 0402LF  page 130 : 1 = P3V3_AUX ; 2 = FM_GPU_PWR_EN_R
R2937  Q_RES  4.7K 5% CHIP  pkg 0402LF  page 130 : 1 = FM_GPU_PWR_EN_R ; 2 = GND
R2939  Q_RES  33.2 1% CHIP  pkg 0402LF  page 81 : 1 = FM_GPU_HSC_EN ; 2 = FM_GPU_HSC_EN_R
R2940  Q_RES  4.7K 5% EMPTY  pkg 0402LF  page 241 : 1 = P3V3_AUX ; 2 = FM_GPU_HSC_EN
R2941  Q_RES  100K 1% CHIP  pkg 0402LF  page 241 : 1 = FM_GPU_HSC_EN ; 2 = GND
R2944  Q_RES  33.2 1% CHIP  pkg 0402LF  page 241 : 1 = FM_GPU_HSC_EN_BUF_R ; 2 = FM_GPU_HSC_EN_BUF
R2946  Q_RES  4.7K 5% EMPTY  pkg 0402LF  page 241 : 1 = P3V3_AUX ; 2 = FM_GPU_HSC_EN_BUF_R
R2948  Q_RES  4.7K 5% EMPTY  pkg 0402LF  page 241 : 1 = FM_GPU_HSC_EN_BUF_R ; 2 = GND
R2950  Q_RES  1K 1% CHIP  pkg 0402LF  page 240 : 1 = P3V3_AUX ; 2 = FM_PDB_BUF_EN_R1_N
R2967  Q_RES  0 5% CHIP  pkg 0402LF  page 250 : 1 = SMB_PCIE0_3V3AUX_SCL_R3 ; 2 = SMB_SENSOR_M2_P1_3V3AUX_SCL
R2968  Q_RES  0 5% CHIP  pkg 0402LF  page 250 : 1 = SMB_PCIE0_3V3AUX_SDA_R3 ; 2 = SMB_SENSOR_M2_P1_3V3AUX_SDA
R2982  Q_RES  0 5% CHIP  pkg 0402LF  page 245 : 1 = SMB_IOEXP_3V3AUX_SCL ; 2 = SMB_IOEXP_3V3AUX_SCL_R1
R2983  Q_RES  0 5% CHIP  pkg 0402LF  page 245 : 1 = SMB_IOEXP_3V3AUX_SDA ; 2 = SMB_IOEXP_3V3AUX_SDA_R1
R2984  Q_RES  2.2K 5% CHIP  pkg 0402LF  page 250 : 1 = P3V3_AUX ; 2 = SMB_BMC_SWB_SCL
R2985  Q_RES  2.2K 5% CHIP  pkg 0402LF  page 250 : 1 = P3V3_AUX ; 2 = SMB_BMC_SWB_SDA
R2986  Q_RES  0 5% EMPTY  pkg 0402LF  page 248 : 1 = SMB_2_BMC_GPU_R_SCL ; 2 = SMB_2_BMC_GPU_BUF_R_SCL
R2987  Q_RES  0 5% EMPTY  pkg 0402LF  page 248 : 1 = SMB_2_BMC_GPU_R_SDA ; 2 = SMB_2_BMC_GPU_BUF_R_SDA
R2990  Q_RES  33.2 1% CHIP  pkg 0402LF  page 248 : 1 = SMB_2_BMC_GPU_BUF_R_SCL ; 2 = SMB_2_BMC_GPU_BUF_SCL
R2991  Q_RES  33.2 1% CHIP  pkg 0402LF  page 248 : 1 = SMB_2_BMC_GPU_BUF_R_SDA ; 2 = SMB_2_BMC_GPU_BUF_SDA
R2992  Q_RES  0 5% CHIP  pkg 0402LF  page 248 : 1 = SMB_BMC_GPU_EN ; 2 = SMB_BMC_GPU_EN_R3
R2995  Q_RES  33.2 1% CHIP  pkg 0402LF  page 151 : 1 = SMB_PMBUS_3V3AUX_SCL ; 2 = SMB_SML1_PMBUS_HSC_SCL
R2996  Q_RES  33.2 1% CHIP  pkg 0402LF  page 151 : 1 = SMB_PMBUS_3V3AUX_SDA ; 2 = SMB_SML1_PMBUS_HSC_SDA
R2999  Q_RES  2.2K 5% EMPTY  pkg 0402LF  page 151 : 1 = SMB_2_BMC_GPU_SCL ; 2 = P3V3_AUX
R3004  Q_RES  2.2K 5% EMPTY  pkg 0402LF  page 151 : 1 = SMB_2_BMC_GPU_SDA ; 2 = P3V3_AUX
R3005  Q_RES  18K 1% CHIP  pkg 0402LF  page 257 : 1 = P5V ; 2 = P5V_ADC
R3028  Q_RES  100K 1% EMPTY  pkg 0402LF  page 127 : 1 = FM_SMB_1_ALERT_GPU_N ; 2 = GND
R3029  Q_RES  4.7K 5% CHIP  pkg 0402LF  page 127 : 1 = P3V3_AUX ; 2 = FM_SMB_1_ALERT_GPU
R3030  Q_RES  100K 1% CHIP  pkg 0402LF  page 127 : 1 = P3V3_AUX ; 2 = FM_SMB_1_ALERT_GPU_ISO_N
R3032  Q_RES  100K 1% EMPTY  pkg 0402LF  page 127 : 1 = FM_SMB_2_ALERT_GPU_N ; 2 = GND
R3033  Q_RES  0 5% CHIP  pkg 0402LF  page 130 : 1 = UART_BMC_BIC_RX ; 2 = UART_BMC_BIC_R_RX
R3034  Q_RES  4.7K 5% CHIP  pkg 0402LF  page 127 : 1 = P3V3_AUX ; 2 = FM_SMB_2_ALERT_GPU
R3035  Q_RES  100K 1% CHIP  pkg 0402LF  page 127 : 1 = P3V3_AUX ; 2 = FM_SMB_2_ALERT_GPU_ISO_N
R3036  Q_RES  33.2 1% CHIP  pkg 0402LF  page 130 : 1 = UART_BMC_BIC_R_BUF_RX ; 2 = UART_BMC_BIC_BUF_RX
R3047  Q_RES  0 5% CHIP  pkg 0402LF  page 253 : 1 = MB0_P12V_STBY_PWRGD ; 2 = PWRGD_PS_PWROK_PLD
R3048  Q_RES  0 5% CHIP  pkg 0402LF  page 253 : 1 = MB0_P12V_STBY_PWRGD ; 2 = PWRGD_PS_PWROK
R3062  Q_RES  2K 1% EMPTY  pkg 0402LF  page 151 : 1 = SMB_CPU0_CPU1_APML_SDA ; 2 = P3V3_AUX
R3063  Q_RES  0 5% CHIP  pkg 0402LF  page 130 : 1 = FM_PDB_BUF_EN_R1 ; 2 = FM_UART_EN
R3066  Q_RES  33.2 1% CHIP  pkg 0402LF  page 81 : 1 = FM_SMB_1_ALERT_GPU_ISO_R_N ; 2 = FM_SMB_1_ALERT_GPU_ISO_N
R3069  Q_RES  130 1% CHIP  pkg 0402LF  page 254 : 1 = LED_PWRGD_SYS_PWROK_R ; 2 = P3V3_AUX
R3071  Q_RES  130 1% CHIP  pkg 0402LF  page 254 : 1 = LED_PWRGD_P1V8_AUX ; 2 = P3V3_AUX
R3074  Q_RES  130 1% CHIP  pkg 0402LF  page 254 : 1 = LED_RST_RSMRST_PLD_R_N ; 2 = P3V3_AUX
R3075  Q_RES  130 1% CHIP  pkg 0402LF  page 254 : 1 = LED_PWRGD_PS_PWROK_PLD ; 2 = P3V3_AUX
R3086  Q_RES  130 1% CHIP  pkg 0402LF  page 255 : 1 = LED_PWRGD_PVDD33_S5_R ; 2 = P3V3_AUX
R3087  Q_RES  130 1% CHIP  pkg 0402LF  page 255 : 1 = LED_PWRGD_PVDDCR_CPU0_P0_R ; 2 = P3V3_AUX
R3088  Q_RES  130 1% CHIP  pkg 0402LF  page 255 : 1 = LED_PWRGD_PVDDCR_CPU1_P0_R ; 2 = P3V3_AUX
R3089  Q_RES  130 1% CHIP  pkg 0402LF  page 255 : 1 = LED_PWRGD_PVDDCR_SOC_P0_R ; 2 = P3V3_AUX
R3090  Q_RES  130 1% CHIP  pkg 0402LF  page 255 : 1 = LED_PWRGD_PVDD11_S3_P0_R ; 2 = P3V3_AUX
R3091  Q_RES  130 1% CHIP  pkg 0402LF  page 255 : 1 = LED_PWRGD_PVDD18_S5_P0_R ; 2 = P3V3_AUX
R3092  Q_RES  130 1% CHIP  pkg 0402LF  page 255 : 1 = LED_PWRGD_PVDDIO_P0_R ; 2 = P3V3_AUX
R3093  Q_RES  130 1% CHIP  pkg 0402LF  page 256 : 1 = LED_PWRGD_PVDDCR_CPU0_P1_R ; 2 = P3V3_AUX
R3094  Q_RES  130 1% CHIP  pkg 0402LF  page 256 : 1 = LED_PWRGD_PVDDCR_SOC_P1_R ; 2 = P3V3_AUX
R3095  Q_RES  130 1% CHIP  pkg 0402LF  page 256 : 1 = LED_PWRGD_PVDDIO_P1_R ; 2 = P3V3_AUX
R3096  Q_RES  130 1% CHIP  pkg 0402LF  page 256 : 1 = LED_PWRGD_PVDDCR_CPU1_P1_R ; 2 = P3V3_AUX
R3097  Q_RES  130 1% CHIP  pkg 0402LF  page 256 : 1 = LED_PWRGD_PVDD18_S5_P1_R ; 2 = P3V3_AUX
R3099  Q_RES  130 1% CHIP  pkg 0402LF  page 256 : 1 = LED_PWRGD_PVDD11_S3_P1_R ; 2 = P3V3_AUX
R3100  Q_RES  130 1% CHIP  pkg 0402LF  page 254 : 1 = LED_P3V3 ; 2 = P3V3
R3102  Q_RES  470 1% CHIP  pkg 0402LF  page 254 : 1 = LED_P5V ; 2 = P5V
R3105  Q_RES  0 5% CHIP  pkg 0402LF  page 248 : 1 = SMB_BMC_SWB_SCL ; 2 = SMB_BMC_SWB_R_SCL
R3106  Q_RES  0 5% CHIP  pkg 0402LF  page 248 : 1 = SMB_BMC_SWB_SDA ; 2 = SMB_BMC_SWB_R_SDA
R3107  Q_RES  0 5% CHIP  pkg 0402LF  page 248 : 1 = SMB_2_BMC_GPU_SCL ; 2 = SMB_2_BMC_GPU_R_SCL
R3108  Q_RES  0 5% CHIP  pkg 0402LF  page 248 : 1 = SMB_2_BMC_GPU_SDA ; 2 = SMB_2_BMC_GPU_R_SDA
R3109  Q_RES  0 5% CHIP  pkg 0402LF  page 248 : 1 = SMB_1_BMC_GPU_SCL ; 2 = SMB_1_BMC_GPU_R_SCL
R3110  Q_RES  0 5% CHIP  pkg 0402LF  page 248 : 1 = SMB_1_BMC_GPU_SDA ; 2 = SMB_1_BMC_GPU_R_SDA
R3111  Q_RES  0 5% CHIP  pkg 0402LF  page 248 : 1 = I3C_BMC_SWB_SDA ; 2 = I3C_BMC_SWB_R_SDA
R3112  Q_RES  33.2 1% CHIP  pkg 0402LF  page 248 : 1 = I3C_BMC_SWB_SCL ; 2 = I3C_BMC_SWB_R_SCL
R3113  Q_RES  33.2 1% CHIP  pkg 0402LF  page 240 : 1 = SMB_FAN_3V3AUX_SCL ; 2 = SMB_FAN_3V3AUX_R_SCL
R3114  Q_RES  33.2 1% CHIP  pkg 0402LF  page 240 : 1 = SMB_FAN_3V3AUX_SDA ; 2 = SMB_FAN_3V3AUX_R_SDA
R3117  Q_RES  510K 5% EMPTY  pkg 0402LF  page 190 : 1 = P12V_AUX ; 2 = P3V3_AUX_EN
R3118  Q_RES  86.6K 1% EMPTY  pkg 0402LF  page 190 : 1 = P3V3_AUX_EN ; 2 = GND
R3132  Q_RES  100K 1% CHIP  pkg 0402LF  page 131 : 1 = GND ; 2 = FM_OCP_SFF_PWR_GOOD
R3133  Q_RES  1K 1% CHIP  pkg 0402LF  page 140 : 1 = P3V3_AUX ; 2 = OCP_V3_2_PRSNT0_R_N
R3134  Q_RES  1K 1% CHIP  pkg 0402LF  page 140 : 1 = P3V3_AUX ; 2 = OCP_V3_2_PRSNT2_R_N
R3135  Q_RES  1K 1% CHIP  pkg 0402LF  page 140 : 1 = P3V3_AUX ; 2 = OCP_V3_2_PRSNT1_R_N
R3136  Q_RES  1K 1% CHIP  pkg 0402LF  page 140 : 1 = P3V3_AUX ; 2 = OCP_V3_2_PRSNT3_R_N
R3142  Q_RES  0 5% CHIP  pkg 0402LF  page 140 : 1 = HP_LVC3_OCP_V3_2_PRSNT2_N_R ; 2 = HP_LVC3_OCP_V3_2_PRSNT2_PLD_N
R3144  Q_RES  0 5% CHIP  pkg 0402LF  page 134 : 1 = P12V_OCP_PWRGD_1 ; 2 = HP_LVC3_OCP_V3_1_P12V_PWRGD
R3147  Q_RES  1K 1% CHIP  pkg 0402LF  page 140 : 1 = P3V3_AUX ; 2 = HP_LVC3_OCP_V3_2_PRSNT2_PLD_N
R3162  Q_RES  4.7K 1% CHIP  pkg 0402LF  page 137 : 1 = P3V3_OCP_V3_2 ; 2 = OCP_V3_2_ID0
R3163  Q_RES  4.7K 1% EMPTY  pkg 0402LF  page 137 : 1 = OCP_V3_2_ID0 ; 2 = GND
R3164  Q_RES  10K 1% CHIP  pkg 0402LF  page 137 : 1 = GND ; 2 = OCP_V3_2_AUX_PWR_EN
R3165  Q_RES  10K 1% CHIP  pkg 0402LF  page 137 : 1 = GND ; 2 = OCP_V3_2_MAIN_PWR_EN
R3166  Q_RES  4.7K 1% EMPTY  pkg 0402LF  page 137 : 1 = P3V3_OCP_V3_2 ; 2 = OCP_V3_2_ID1
R3167  Q_RES  4.7K 1% CHIP  pkg 0402LF  page 137 : 1 = OCP_V3_2_ID1 ; 2 = GND
R3168  Q_RES  0 5% CHIP  pkg 0402LF  page 137 : 1 = OCP_V3_2_MAIN_PWR_EN ; 2 = OCP_V3_2_MAIN_PWR_EN_R
R3169  Q_RES  0 5% CHIP  pkg 0402LF  page 137 : 1 = OCP_V3_2_ISO_BIF0_EN ; 2 = OCP_V3_2_BIF0_R_N
R3170  Q_RES  0 5% CHIP  pkg 0402LF  page 137 : 1 = OCP_V3_2_ISO_BIF1_EN ; 2 = OCP_V3_2_BIF1_R_N
R3171  Q_RES  0 5% CHIP  pkg 0402LF  page 137 : 1 = OCP_V3_2_ISO_BIF2_EN ; 2 = OCP_V3_2_BIF2_R_N
R3172  Q_RES  0 5% CHIP  pkg 0402LF  page 137 : 1 = OCP_V3_2_AUX_PWR_EN ; 2 = OCP_V3_2_AUX_PWR_EN_R
R3173  Q_RES  1K 1% CHIP  pkg 0402LF  page 137 : 1 = SGPIO_OCP_V3_2_LD_N ; 2 = P3V3_OCP_V3_2
R3174  Q_RES  10K 1% CHIP  pkg 0402LF  page 137 : 1 = SGPIO_OCP_V3_2_DATAIN ; 2 = P3V3_OCP_V3_2
R3175  Q_RES  10K 1% CHIP  pkg 0402LF  page 137 : 1 = SGPIO_OCP_V3_2_DATAOUT ; 2 = GND
R3176  Q_RES  1K 1% CHIP  pkg 0402LF  page 137 : 1 = SGPIO_OCP_V3_2_CLK ; 2 = P3V3_OCP_V3_2
R3177  Q_RES  0 5% CHIP  pkg 0402LF  page 137 : 1 = USB2_P10_DN ; 2 = USB2_CPU0_P10_DN
R3178  Q_RES  0 5% CHIP  pkg 0402LF  page 137 : 1 = USB2_P10_DP ; 2 = USB2_CPU0_P10_DP
R3180  Q_RES  0 5% CHIP  pkg 0402LF  page 137 : 1 = OCP_V3_2_PRSNTA_R_N ; 2 = GND
R3181  Q_RES  27.4 1% CHIP  pkg 0402LF  page 133 : 1 = CLK_50M_NCSI_OCP_2 ; 2 = CLK_50M_NCSI_OCP_V3_2
R3182  Q_RES  10K 1% CHIP  pkg 0402LF  page 139 : 1 = P3V3_OCP_V3_2 ; 2 = IRQ_LVC3_OCP_V3_2_WAKE_N
R3183  Q_RES  10K 1% CHIP  pkg 0402LF  page 139 : 1 = P3V3_OCP_V3_2 ; 2 = PU_OCP_V3_2_WAKE_OE
R3184  Q_RES  4.7K 1% CHIP  pkg 0402LF  page 139 : 1 = P3V3_AUX ; 2 = OCP_V3_2_WAKE_BUFF_N
R3185  Q_RES  33.2 1% CHIP  pkg 0402LF  page 139 : 1 = OCP_V3_2_WAKE_BUFF_N ; 2 = OCP_V3_2_WAKE_BUFF_R_N
